(kicad_pcb
	(version 20260206)
	(generator "pcbnew")
	(generator_version "10.0")
	(general
		(thickness 1.6)
		(legacy_teardrops no)
	)
	(paper "A4")
	(title_block
		(title "Bryce Canyon_IOM_IOC_16318-2_OCP.brd")
		(comment 1 "Bryce Canyon / footprints 919-925 of 1605")
	)
	(layers
		(0 "F.Cu" signal "TOP")
		(4 "In1.Cu" signal "L2GND")
		(6 "In2.Cu" signal "L3")
		(8 "In3.Cu" signal "L4VCC")
		(10 "In4.Cu" signal "L5VCC")
		(12 "In5.Cu" signal "L6")
		(14 "In6.Cu" signal "L7GND")
		(2 "B.Cu" signal "BOTTOM")
		(9 "F.Adhes" user "F.Adhesive")
		(11 "B.Adhes" user "B.Adhesive")
		(13 "F.Paste" user "Package Geometry/Pastemask Top")
		(15 "B.Paste" user "Package Geometry/Pastemask Bottom")
		(5 "F.SilkS" user "Ref Des/Silkscreen Top")
		(7 "B.SilkS" user "Ref Des/Silkscreen Bottom")
		(1 "F.Mask" user "Board Geometry/Soldermask Top")
		(3 "B.Mask" user "Board Geometry/Soldermask Bottom")
		(17 "Dwgs.User" user "User.Drawings")
		(19 "Cmts.User" user "User.Comments")
		(21 "Eco1.User" user "User.Eco1")
		(23 "Eco2.User" user "User.Eco2")
		(25 "Edge.Cuts" user "Board Geometry/Outline")
		(27 "Margin" user)
		(31 "F.CrtYd" user "Package Geometry/Place Bound Top")
		(29 "B.CrtYd" user "Package Geometry/Place Bound Bottom")
		(35 "F.Fab" user "Ref Des/Assembly Top")
		(33 "B.Fab" user "Ref Des/Assembly Bottom")
	)
	(footprint ""
		(layer "F.Cu")
		(at 38.5826 -161.4424)
		(property "Reference" "R299"
			(at 0 0 0)
			(layer "F.SilkS")
			(hide yes)
			(effects
				(font
					(size 1.27 1.27)
				)
			)
		)
		(property "Value" "4K7R2F-GP"
			(at 0.064008 -3.993896 0)
			(unlocked yes)
			(layer "F.Fab")
			(hide yes)
			(effects
				(font
					(size 1.016 1.016)
					(thickness 0.1524)
				)
			)
		)
		(property "Device Type" "R402H16"
			(at 0.064008 -5.517896 0)
			(unlocked yes)
			(layer "F.Fab")
			(hide yes)
			(effects
				(font
					(size 1.016 1.016)
					(thickness 0.1524)
				)
			)
		)
		(duplicate_pad_numbers_are_jumpers no)
		(fp_line
			(start -0.508 -0.9398)
			(end -0.508 0.9398)
			(stroke
				(width 0.1524)
				(type default)
			)
			(layer "F.SilkS")
		)
		(fp_line
			(start 0.508 -0.9398)
			(end -0.508 -0.9398)
			(stroke
				(width 0.1524)
				(type default)
			)
			(layer "F.SilkS")
		)
		(fp_rect
			(start -0.508 0.9398)
			(end 0.508 -0.9398)
			(stroke
				(width 0)
				(type default)
			)
			(fill no)
			(layer "F.CrtYd")
		)
		(fp_rect
			(start -0.508 0.9398)
			(end 0.508 -0.9398)
			(stroke
				(width 0)
				(type default)
			)
			(fill no)
			(layer "F.Fab")
		)
		(pad "1" smd custom
			(at 0 -0.4445)
			(size 0.1397 0.1397)
			(layers "F.Cu" "F.Mask" "F.Paste")
			(net "P3V3_STBY")
			(options
				(clearance outline)
				(anchor circle)
			)
			(primitives
				(gr_poly
					(pts
						(arc
							(start -0.1778 -0.2794)
							(mid -0.249642 -0.249642)
							(end -0.2794 -0.1778)
						)
						(arc
							(start -0.2794 0.1778)
							(mid -0.249642 0.249642)
							(end -0.1778 0.2794)
						)
						(arc
							(start 0.1778 0.2794)
							(mid 0.249642 0.249642)
							(end 0.2794 0.1778)
						)
						(arc
							(start 0.2794 -0.1778)
							(mid 0.249642 -0.249642)
							(end 0.1778 -0.2794)
						)
					)
					(width 0)
					(fill yes)
				)
			)
		)
		(pad "2" smd custom
			(at 0 0.4445)
			(size 0.1397 0.1397)
			(layers "F.Cu" "F.Mask" "F.Paste")
			(net "UART_BMC_COMP_IN_RX")
			(options
				(clearance outline)
				(anchor circle)
			)
			(primitives
				(gr_poly
					(pts
						(arc
							(start -0.1778 -0.2794)
							(mid -0.249642 -0.249642)
							(end -0.2794 -0.1778)
						)
						(arc
							(start -0.2794 0.1778)
							(mid -0.249642 0.249642)
							(end -0.1778 0.2794)
						)
						(arc
							(start 0.1778 0.2794)
							(mid 0.249642 0.249642)
							(end 0.2794 0.1778)
						)
						(arc
							(start 0.2794 -0.1778)
							(mid 0.249642 -0.249642)
							(end 0.1778 -0.2794)
						)
					)
					(width 0)
					(fill yes)
				)
			)
		)
	)
	(footprint ""
		(layer "F.Cu")
		(at 180.42382 -124.60478 180)
		(property "Reference" "D5"
			(at 0 0 180)
			(layer "F.SilkS")
			(hide yes)
			(effects
				(font
					(size 1.27 1.27)
				)
			)
		)
		(property "Value" "SMF15A-GP"
			(at -2.0955 1.2192 180)
			(unlocked yes)
			(layer "F.Fab")
			(hide yes)
			(effects
				(font
					(size 1.016 1.016)
					(thickness 0.1524)
				)
			)
		)
		(property "Device Type" "SOD123AK-2H43"
			(at -2.0955 -0.3048 180)
			(unlocked yes)
			(layer "F.Fab")
			(hide yes)
			(effects
				(font
					(size 1.016 1.016)
					(thickness 0.1524)
				)
			)
		)
		(duplicate_pad_numbers_are_jumpers no)
		(fp_line
			(start 1.1557 2.921)
			(end -1.1557 2.921)
			(stroke
				(width 0.508)
				(type default)
			)
			(layer "F.SilkS")
		)
		(fp_line
			(start 1.1557 2.7686)
			(end 1.1557 -2.7686)
			(stroke
				(width 0.1524)
				(type default)
			)
			(layer "F.SilkS")
		)
		(fp_line
			(start 1.1557 -2.7686)
			(end -1.1557 -2.7686)
			(stroke
				(width 0.1524)
				(type default)
			)
			(layer "F.SilkS")
		)
		(fp_line
			(start -1.1557 2.7686)
			(end 1.1557 2.7686)
			(stroke
				(width 0.1524)
				(type default)
			)
			(layer "F.SilkS")
		)
		(fp_line
			(start -1.1557 -2.7686)
			(end -1.1557 2.7686)
			(stroke
				(width 0.1524)
				(type default)
			)
			(layer "F.SilkS")
		)
		(fp_poly
			(pts
				(xy -0.4572 1.8669) (xy -0.4572 1.397) (xy -0.9017 1.397) (xy -0.9017 -1.397) (xy -0.4572 -1.397)
				(xy -0.4572 -1.8669) (xy 0.4572 -1.8669) (xy 0.4572 -1.397) (xy 0.9017 -1.397) (xy 0.9017 1.397)
				(xy 0.4572 1.397) (xy 0.4572 1.8669)
			)
			(stroke
				(width 0)
				(type default)
			)
			(fill no)
			(layer "F.CrtYd")
		)
		(fp_poly
			(pts
				(xy -1.4097 2.8448) (xy -1.4097 -2.8448) (xy 1.4097 -2.8448) (xy 1.4097 1.3716) (xy 0.9017 1.3716)
				(xy 0.9017 -1.397) (xy 0.4572 -1.397) (xy 0.4572 -1.8669) (xy -0.4572 -1.8669) (xy -0.4572 -1.397)
				(xy -0.9017 -1.397) (xy -0.9017 1.397) (xy -0.4572 1.397) (xy -0.4572 1.8669) (xy 0.4572 1.8669)
				(xy 0.4572 1.397) (xy 0.9017 1.397) (xy 0.9017 1.3843) (xy 1.4097 1.3843) (xy 1.4097 2.8448)
			)
			(stroke
				(width 0)
				(type default)
			)
			(fill no)
			(layer "F.CrtYd")
		)
		(fp_rect
			(start -1.4097 2.8448)
			(end 1.4097 -2.8448)
			(stroke
				(width 0)
				(type default)
			)
			(fill no)
			(layer "F.Fab")
		)
		(pad "A" smd rect
			(at 0 -1.75768 180)
			(size 1.143 1.4986)
			(layers "F.Cu" "F.Mask" "F.Paste")
			(net "P1V8_EN")
		)
		(pad "K" smd rect
			(at 0 1.75768 180)
			(size 1.143 1.4986)
			(layers "F.Cu" "F.Mask" "F.Paste")
			(net "P3V3_PG")
		)
	)
	(footprint ""
		(layer "F.Cu")
		(at 79.67218 -178.479196 180)
		(property "Reference" "C193"
			(at 0 0 180)
			(layer "F.SilkS")
			(hide yes)
			(effects
				(font
					(size 1.27 1.27)
				)
			)
		)
		(property "Value" "SC10U6D3V5KX-4GP"
			(at -0.0762 -6.1214 180)
			(unlocked yes)
			(layer "F.Fab")
			(hide yes)
			(effects
				(font
					(size 1.016 1.016)
					(thickness 0.1524)
				)
			)
		)
		(property "Device Type" "C805H58"
			(at -0.0762 -8.1534 180)
			(unlocked yes)
			(layer "F.Fab")
			(hide yes)
			(effects
				(font
					(size 1.016 1.016)
					(thickness 0.1524)
				)
			)
		)
		(duplicate_pad_numbers_are_jumpers no)
		(fp_line
			(start 0.635 0)
			(end -0.635 0)
			(stroke
				(width 0.508)
				(type default)
			)
			(layer "F.SilkS")
		)
		(fp_rect
			(start -0.9652 1.778)
			(end 0.9652 -1.778)
			(stroke
				(width 0)
				(type default)
			)
			(fill no)
			(layer "F.CrtYd")
		)
		(fp_poly
			(pts
				(xy -0.9652 -1.778) (xy 0.9652 -1.778) (xy 0.9652 1.778) (xy -0.9652 1.778)
			)
			(stroke
				(width 0)
				(type default)
			)
			(fill no)
			(layer "F.Fab")
		)
		(pad "1" smd rect
			(at 0 -0.9652 180)
			(size 1.397 1.143)
			(layers "F.Cu" "F.Mask" "F.Paste")
			(net "TPS74801_P2V5_STBY_OUT")
		)
		(pad "2" smd rect
			(at 0 0.9652 180)
			(size 1.397 1.143)
			(layers "F.Cu" "F.Mask" "F.Paste")
			(net "GND")
		)
	)
	(footprint ""
		(layer "F.Cu")
		(at 121.2342 -16.002 180)
		(property "Reference" "C129"
			(at 0 0 180)
			(layer "F.SilkS")
			(hide yes)
			(effects
				(font
					(size 1.27 1.27)
				)
			)
		)
		(property "Value" "SC1KP50V2KX-1GP"
			(at 1.1811 -2.7051 180)
			(unlocked yes)
			(layer "F.Fab")
			(hide yes)
			(effects
				(font
					(size 1.016 1.016)
					(thickness 0.1524)
				)
			)
		)
		(property "Device Type" "C402H22"
			(at 1.1811 -4.2291 180)
			(unlocked yes)
			(layer "F.Fab")
			(hide yes)
			(effects
				(font
					(size 1.016 1.016)
					(thickness 0.1524)
				)
			)
		)
		(duplicate_pad_numbers_are_jumpers no)
		(fp_rect
			(start -0.4318 0.9525)
			(end 0.4318 -0.9525)
			(stroke
				(width 0)
				(type default)
			)
			(fill no)
			(layer "F.CrtYd")
		)
		(fp_rect
			(start -0.4318 0.9525)
			(end 0.4318 -0.9525)
			(stroke
				(width 0)
				(type default)
			)
			(fill no)
			(layer "F.Fab")
		)
		(pad "1" smd custom
			(at 0 -0.4445 180)
			(size 0.1524 0.1524)
			(layers "F.Cu" "F.Mask" "F.Paste")
			(net "MB0_TEMP")
			(options
				(clearance outline)
				(anchor circle)
			)
			(primitives
				(gr_poly
					(pts
						(arc
							(start 0.3048 -0.2032)
							(mid 0.275042 -0.275042)
							(end 0.2032 -0.3048)
						)
						(arc
							(start -0.2032 -0.3048)
							(mid -0.275042 -0.275042)
							(end -0.3048 -0.2032)
						)
						(arc
							(start -0.3048 0.2032)
							(mid -0.275042 0.275042)
							(end -0.2032 0.3048)
						)
						(arc
							(start 0.2032 0.3048)
							(mid 0.275042 0.275042)
							(end 0.3048 0.2032)
						)
					)
					(width 0)
					(fill yes)
				)
			)
		)
		(pad "2" smd custom
			(at 0 0.4445 180)
			(size 0.1524 0.1524)
			(layers "F.Cu" "F.Mask" "F.Paste")
			(net "GND")
			(options
				(clearance outline)
				(anchor circle)
			)
			(primitives
				(gr_poly
					(pts
						(arc
							(start 0.3048 -0.2032)
							(mid 0.275042 -0.275042)
							(end 0.2032 -0.3048)
						)
						(arc
							(start -0.2032 -0.3048)
							(mid -0.275042 -0.275042)
							(end -0.3048 -0.2032)
						)
						(arc
							(start -0.3048 0.2032)
							(mid -0.275042 0.275042)
							(end -0.2032 0.3048)
						)
						(arc
							(start 0.2032 0.3048)
							(mid 0.275042 0.275042)
							(end 0.3048 0.2032)
						)
					)
					(width 0)
					(fill yes)
				)
			)
		)
	)
	(footprint ""
		(layer "F.Cu")
		(at 205.1304 -120.269 -90)
		(property "Reference" "R544"
			(at 0 0 270)
			(layer "F.SilkS")
			(hide yes)
			(effects
				(font
					(size 1.27 1.27)
				)
			)
		)
		(property "Value" "4K22R2F-GP"
			(at 0.064008 -3.993896 270)
			(unlocked yes)
			(layer "F.Fab")
			(hide yes)
			(effects
				(font
					(size 1.016 1.016)
					(thickness 0.1524)
				)
			)
		)
		(property "Device Type" "R402H16"
			(at 0.064008 -5.517896 270)
			(unlocked yes)
			(layer "F.Fab")
			(hide yes)
			(effects
				(font
					(size 1.016 1.016)
					(thickness 0.1524)
				)
			)
		)
		(duplicate_pad_numbers_are_jumpers no)
		(fp_line
			(start -0.508 -0.9398)
			(end -0.508 0.9398)
			(stroke
				(width 0.1524)
				(type default)
			)
			(layer "F.SilkS")
		)
		(fp_line
			(start 0.508 -0.9398)
			(end -0.508 -0.9398)
			(stroke
				(width 0.1524)
				(type default)
			)
			(layer "F.SilkS")
		)
		(fp_rect
			(start -0.508 0.9398)
			(end 0.508 -0.9398)
			(stroke
				(width 0)
				(type default)
			)
			(fill no)
			(layer "F.CrtYd")
		)
		(fp_rect
			(start -0.508 0.9398)
			(end 0.508 -0.9398)
			(stroke
				(width 0)
				(type default)
			)
			(fill no)
			(layer "F.Fab")
		)
		(pad "1" smd custom
			(at 0 -0.4445 270)
			(size 0.1397 0.1397)
			(layers "F.Cu" "F.Mask" "F.Paste")
			(net "P1V5_OUT")
			(options
				(clearance outline)
				(anchor circle)
			)
			(primitives
				(gr_poly
					(pts
						(arc
							(start -0.1778 -0.2794)
							(mid -0.249642 -0.249642)
							(end -0.2794 -0.1778)
						)
						(arc
							(start -0.2794 0.1778)
							(mid -0.249642 0.249642)
							(end -0.1778 0.2794)
						)
						(arc
							(start 0.1778 0.2794)
							(mid 0.249642 0.249642)
							(end 0.2794 0.1778)
						)
						(arc
							(start 0.2794 -0.1778)
							(mid 0.249642 -0.249642)
							(end 0.1778 -0.2794)
						)
					)
					(width 0)
					(fill yes)
				)
			)
		)
		(pad "2" smd custom
			(at 0 0.4445 270)
			(size 0.1397 0.1397)
			(layers "F.Cu" "F.Mask" "F.Paste")
			(net "TPS74801_P1V5_FB")
			(options
				(clearance outline)
				(anchor circle)
			)
			(primitives
				(gr_poly
					(pts
						(arc
							(start -0.1778 -0.2794)
							(mid -0.249642 -0.249642)
							(end -0.2794 -0.1778)
						)
						(arc
							(start -0.2794 0.1778)
							(mid -0.249642 0.249642)
							(end -0.1778 0.2794)
						)
						(arc
							(start 0.1778 0.2794)
							(mid 0.249642 0.249642)
							(end 0.2794 0.1778)
						)
						(arc
							(start 0.2794 -0.1778)
							(mid 0.249642 -0.249642)
							(end 0.1778 -0.2794)
						)
					)
					(width 0)
					(fill yes)
				)
			)
		)
	)
	(footprint ""
		(layer "F.Cu")
		(at 28.194 -156.718 -90)
		(property "Reference" "R786"
			(at 0 0 270)
			(layer "F.SilkS")
			(hide yes)
			(effects
				(font
					(size 1.27 1.27)
				)
			)
		)
		(property "Value" "0R2J-2-GP"
			(at 0.064008 -3.993896 270)
			(unlocked yes)
			(layer "F.Fab")
			(hide yes)
			(effects
				(font
					(size 1.016 1.016)
					(thickness 0.1524)
				)
			)
		)
		(property "Device Type" "R402H16"
			(at 0.064008 -5.517896 270)
			(unlocked yes)
			(layer "F.Fab")
			(hide yes)
			(effects
				(font
					(size 1.016 1.016)
					(thickness 0.1524)
				)
			)
		)
		(duplicate_pad_numbers_are_jumpers no)
		(fp_line
			(start -0.508 -0.9398)
			(end -0.508 0.9398)
			(stroke
				(width 0.1524)
				(type default)
			)
			(layer "F.SilkS")
		)
		(fp_line
			(start 0.508 -0.9398)
			(end -0.508 -0.9398)
			(stroke
				(width 0.1524)
				(type default)
			)
			(layer "F.SilkS")
		)
		(fp_rect
			(start -0.508 0.9398)
			(end 0.508 -0.9398)
			(stroke
				(width 0)
				(type default)
			)
			(fill no)
			(layer "F.CrtYd")
		)
		(fp_rect
			(start -0.508 0.9398)
			(end 0.508 -0.9398)
			(stroke
				(width 0)
				(type default)
			)
			(fill no)
			(layer "F.Fab")
		)
		(pad "1" smd custom
			(at 0 -0.4445 270)
			(size 0.1397 0.1397)
			(layers "F.Cu" "F.Mask" "F.Paste")
			(net "FLA0_WP_N_R")
			(options
				(clearance outline)
				(anchor circle)
			)
			(primitives
				(gr_poly
					(pts
						(arc
							(start -0.1778 -0.2794)
							(mid -0.249642 -0.249642)
							(end -0.2794 -0.1778)
						)
						(arc
							(start -0.2794 0.1778)
							(mid -0.249642 0.249642)
							(end -0.1778 0.2794)
						)
						(arc
							(start 0.1778 0.2794)
							(mid 0.249642 0.249642)
							(end 0.2794 0.1778)
						)
						(arc
							(start 0.2794 -0.1778)
							(mid 0.249642 -0.249642)
							(end 0.1778 -0.2794)
						)
					)
					(width 0)
					(fill yes)
				)
			)
		)
		(pad "2" smd custom
			(at 0 0.4445 270)
			(size 0.1397 0.1397)
			(layers "F.Cu" "F.Mask" "F.Paste")
			(net "FLA0_WP_N")
			(options
				(clearance outline)
				(anchor circle)
			)
			(primitives
				(gr_poly
					(pts
						(arc
							(start -0.1778 -0.2794)
							(mid -0.249642 -0.249642)
							(end -0.2794 -0.1778)
						)
						(arc
							(start -0.2794 0.1778)
							(mid -0.249642 0.249642)
							(end -0.1778 0.2794)
						)
						(arc
							(start 0.1778 0.2794)
							(mid 0.249642 0.249642)
							(end 0.2794 0.1778)
						)
						(arc
							(start 0.2794 -0.1778)
							(mid 0.249642 -0.249642)
							(end 0.1778 -0.2794)
						)
					)
					(width 0)
					(fill yes)
				)
			)
		)
	)
	(footprint ""
		(layer "F.Cu")
		(at 175.8569 -124.387864 -90)
		(property "Reference" "Q6"
			(at 0 0 270)
			(layer "F.SilkS")
			(hide yes)
			(effects
				(font
					(size 1.27 1.27)
				)
			)
		)
		(property "Value" "2N7002K-1-GP"
			(at 0.127 -8.9662 270)
			(unlocked yes)
			(layer "F.Fab")
			(hide yes)
			(effects
				(font
					(size 1.016 1.016)
					(thickness 0.1524)
				)
			)
		)
		(property "Device Type" "SOT23DGS2D4H44"
			(at 0.127 -10.4902 270)
			(unlocked yes)
			(layer "F.Fab")
			(hide yes)
			(effects
				(font
					(size 1.016 1.016)
					(thickness 0.1524)
				)
			)
		)
		(duplicate_pad_numbers_are_jumpers no)
		(fp_line
			(start -1.651 1.778)
			(end 1.651 1.778)
			(stroke
				(width 0.1524)
				(type default)
			)
			(layer "F.SilkS")
		)
		(fp_line
			(start 1.651 1.778)
			(end 1.651 -1.778)
			(stroke
				(width 0.1524)
				(type default)
			)
			(layer "F.SilkS")
		)
		(fp_line
			(start -1.651 -1.778)
			(end -1.651 1.778)
			(stroke
				(width 0.1524)
				(type default)
			)
			(layer "F.SilkS")
		)
		(fp_line
			(start 1.651 -1.778)
			(end -1.651 -1.778)
			(stroke
				(width 0.1524)
				(type default)
			)
			(layer "F.SilkS")
		)
		(fp_poly
			(pts
				(xy -1.778 1.8796) (xy -1.778 -1.8796) (xy 1.778 -1.8796) (xy 1.778 1.8796)
			)
			(stroke
				(width 0)
				(type default)
			)
			(fill no)
			(layer "F.CrtYd")
		)
		(fp_poly
			(pts
				(xy -1.778 1.8796) (xy -1.778 -1.8796) (xy 1.778 -1.8796) (xy 1.778 1.8796)
			)
			(stroke
				(width 0)
				(type default)
			)
			(fill no)
			(layer "F.Fab")
		)
		(pad "D" smd custom
			(at 0 -0.9525 270)
			(size 0.1905 0.1905)
			(layers "F.Cu" "F.Mask" "F.Paste")
			(net "P3V3_PG")
			(options
				(clearance outline)
				(anchor circle)
			)
			(primitives
				(gr_poly
					(pts
						(arc
							(start -0.1778 0.5715)
							(mid -0.321484 0.511984)
							(end -0.381 0.3683)
						)
						(arc
							(start -0.381 -0.3683)
							(mid -0.321484 -0.511984)
							(end -0.1778 -0.5715)
						)
						(arc
							(start 0.1778 -0.5715)
							(mid 0.321484 -0.511984)
							(end 0.381 -0.3683)
						)
						(arc
							(start 0.381 0.3683)
							(mid 0.321484 0.511984)
							(end 0.1778 0.5715)
						)
					)
					(width 0)
					(fill yes)
				)
			)
		)
		(pad "G" smd custom
			(at -0.98425 0.9525 270)
			(size 0.1905 0.1905)
			(layers "F.Cu" "F.Mask" "F.Paste")
			(net "Q6_G")
			(options
				(clearance outline)
				(anchor circle)
			)
			(primitives
				(gr_poly
					(pts
						(arc
							(start -0.1778 0.5715)
							(mid -0.321484 0.511984)
							(end -0.381 0.3683)
						)
						(arc
							(start -0.381 -0.3683)
							(mid -0.321484 -0.511984)
							(end -0.1778 -0.5715)
						)
						(arc
							(start 0.1778 -0.5715)
							(mid 0.321484 -0.511984)
							(end 0.381 -0.3683)
						)
						(arc
							(start 0.381 0.3683)
							(mid 0.321484 0.511984)
							(end 0.1778 0.5715)
						)
					)
					(width 0)
					(fill yes)
				)
			)
		)
		(pad "S" smd custom
			(at 0.98425 0.9525 270)
			(size 0.1905 0.1905)
			(layers "F.Cu" "F.Mask" "F.Paste")
			(net "GND")
			(options
				(clearance outline)
				(anchor circle)
			)
			(primitives
				(gr_poly
					(pts
						(arc
							(start -0.1778 0.5715)
							(mid -0.321484 0.511984)
							(end -0.381 0.3683)
						)
						(arc
							(start -0.381 -0.3683)
							(mid -0.321484 -0.511984)
							(end -0.1778 -0.5715)
						)
						(arc
							(start 0.1778 -0.5715)
							(mid 0.321484 -0.511984)
							(end 0.381 -0.3683)
						)
						(arc
							(start 0.381 0.3683)
							(mid 0.321484 0.511984)
							(end 0.1778 0.5715)
						)
					)
					(width 0)
					(fill yes)
				)
			)
		)
	)
)
